# BASEBOARD_FAB2 (Tioga Pass) — schematic netlist excerpt (pin names and nets, part order shuffled) for the footprints in the layout excerpt that follows; sources: Cadence DE-HDL packaged netlist, KiCad conversion of Wiwynn_Tioga_Pass_MB.brd

C3N3  CAP_A  1.0UF 6.3V 10% X6S  pkg 0402V  page 132 : A = PVNN_PCH_STBY ; B = GND
C2L44  CAP_A  0.01UF 25V 10% X7R  pkg 0402V  page 173 : A = SATA6G_P1_TX_C_DN ; B = SATA6G_PCH_PCIE_UP_SATA_TXN<1>
R7G7  RES  4.75K 1% CHIP  pkg 0402  page 94 : A = P3V3 ; B = H_CPU0_MEMABC_MEMHOT

(kicad_pcb
	(version 20260206)
	(generator "pcbnew")
	(generator_version "10.0")
	(general
		(thickness 1.6)
		(legacy_teardrops no)
	)
	(paper "A4")
	(title_block
		(title "Wiwynn_Tioga_Pass_MB.brd")
		(comment 1 "Tioga Pass / footprints 3709-3711 of 4770")
	)
	(layers
		(0 "F.Cu" signal "TOP")
		(4 "In1.Cu" signal "L2GND")
		(6 "In2.Cu" signal "L3")
		(8 "In3.Cu" signal "L4GND")
		(10 "In4.Cu" signal "L5")
		(12 "In5.Cu" signal "L6GND")
		(14 "In6.Cu" signal "L7VCC")
		(16 "In7.Cu" signal "L8VCC")
		(18 "In8.Cu" signal "L9GND")
		(20 "In9.Cu" signal "L10")
		(22 "In10.Cu" signal "L11GND")
		(24 "In11.Cu" signal "L12")
		(26 "In12.Cu" signal "L13GND")
		(2 "B.Cu" signal "BOTTOM")
		(9 "F.Adhes" user "F.Adhesive")
		(11 "B.Adhes" user "B.Adhesive")
		(13 "F.Paste" user "Package Geometry/Pastemask Top")
		(15 "B.Paste" user "Package Geometry/Pastemask Bottom")
		(5 "F.SilkS" user "Ref Des/Silkscreen Top")
		(7 "B.SilkS" user "Ref Des/Silkscreen Bottom")
		(1 "F.Mask" user "Board Geometry/Soldermask Top")
		(3 "B.Mask" user "Board Geometry/Soldermask Bottom")
		(17 "Dwgs.User" user "User.Drawings")
		(19 "Cmts.User" user "User.Comments")
		(21 "Eco1.User" user "User.Eco1")
		(23 "Eco2.User" user "User.Eco2")
		(25 "Edge.Cuts" user "Board Geometry/Outline")
		(27 "Margin" user)
		(31 "F.CrtYd" user "Package Geometry/Place Bound Top")
		(29 "B.CrtYd" user "Package Geometry/Place Bound Bottom")
		(35 "F.Fab" user "Ref Des/Assembly Top")
		(33 "B.Fab" user "Ref Des/Assembly Bottom")
	)
	(footprint ""
		(layer "B.Cu")
		(at 421.513 -141.9606)
		(property "Reference" "C2L44"
			(at 0 0 0)
			(layer "B.SilkS")
			(hide yes)
			(effects
				(font
					(size 1.27 1.27)
				)
				(justify mirror)
			)
		)
		(property "Value" ""
			(at 0 0 0)
			(layer "B.Fab")
			(effects
				(font
					(size 1.27 1.27)
				)
				(justify mirror)
			)
		)
		(duplicate_pad_numbers_are_jumpers no)
		(fp_poly
			(pts
				(xy -0.3048 -0.1016) (xy -0.3048 0.9906) (xy 0.3048 0.9906) (xy 0.3048 -0.1016)
			)
			(stroke
				(width 0)
				(type default)
			)
			(fill no)
			(layer "B.CrtYd")
		)
		(fp_line
			(start -0.3048 -0.1016)
			(end 0.3048 -0.1016)
			(stroke
				(width 0.1)
				(type default)
			)
			(layer "B.Fab")
		)
		(fp_line
			(start -0.3048 0.9906)
			(end -0.3048 -0.1016)
			(stroke
				(width 0.1)
				(type default)
			)
			(layer "B.Fab")
		)
		(fp_line
			(start 0.3048 -0.1016)
			(end 0.3048 0.9906)
			(stroke
				(width 0.1)
				(type default)
			)
			(layer "B.Fab")
		)
		(fp_line
			(start 0.3048 0.9906)
			(end -0.3048 0.9906)
			(stroke
				(width 0.1)
				(type default)
			)
			(layer "B.Fab")
		)
		(pad "1" smd rect
			(at 0 0 180)
			(size 0.508 0.508)
			(layers "B.Cu" "B.Mask" "B.Paste")
			(net "SATA6G_P1_TX_C_DN")
		)
		(pad "2" smd rect
			(at 0 0.889 180)
			(size 0.508 0.508)
			(layers "B.Cu" "B.Mask" "B.Paste")
			(net "SATA6G_PCH_PCIE_UP_SATA_TXN<1>")
		)
		(zone
			(layer "B.Cu")
			(hatch none 0.5)
			(connect_pads
				(clearance 0)
			)
			(min_thickness 0.25)
			(keepout
				(tracks allowed)
				(vias not_allowed)
				(pads allowed)
				(copperpour not_allowed)
				(footprints allowed)
			)
			(placement
				(enabled no)
				(sheetname "")
			)
			(fill
				(thermal_gap 0.5)
				(thermal_bridge_width 0.5)
				(island_removal_mode 0)
			)
			(polygon
				(pts
					(xy 421.767 -141.7066) (xy 421.259 -141.7066) (xy 421.259 -141.3256) (xy 421.767 -141.3256)
				)
			)
		)
		(zone
			(layer "B.Cu")
			(hatch none 0.5)
			(connect_pads
				(clearance 0)
			)
			(min_thickness 0.25)
			(keepout
				(tracks not_allowed)
				(vias allowed)
				(pads allowed)
				(copperpour not_allowed)
				(footprints allowed)
			)
			(placement
				(enabled no)
				(sheetname "")
			)
			(fill
				(thermal_gap 0.5)
				(thermal_bridge_width 0.5)
				(island_removal_mode 0)
			)
			(polygon
				(pts
					(xy 421.767 -141.3256) (xy 421.259 -141.3256) (xy 421.259 -141.7066) (xy 421.767 -141.7066)
				)
			)
		)
	)
	(footprint ""
		(layer "B.Cu")
		(at 383.73685 -111.85525 180)
		(property "Reference" "C3N3"
			(at 0 0 0)
			(layer "B.SilkS")
			(hide yes)
			(effects
				(font
					(size 1.27 1.27)
				)
				(justify mirror)
			)
		)
		(property "Value" ""
			(at 0 0 0)
			(layer "B.Fab")
			(effects
				(font
					(size 1.27 1.27)
				)
				(justify mirror)
			)
		)
		(duplicate_pad_numbers_are_jumpers no)
		(fp_rect
			(start 0.2794 0.9144)
			(end -0.2794 -0.1143)
			(stroke
				(width 0)
				(type default)
			)
			(fill no)
			(layer "B.CrtYd")
		)
		(fp_line
			(start 0.2794 0.9144)
			(end 0.2794 -0.1143)
			(stroke
				(width 0.1)
				(type default)
			)
			(layer "B.Fab")
		)
		(fp_line
			(start 0.2794 -0.1143)
			(end -0.2794 -0.1143)
			(stroke
				(width 0.1)
				(type default)
			)
			(layer "B.Fab")
		)
		(fp_line
			(start -0.2794 0.9144)
			(end 0.2794 0.9144)
			(stroke
				(width 0.1)
				(type default)
			)
			(layer "B.Fab")
		)
		(fp_line
			(start -0.2794 -0.1143)
			(end -0.2794 0.9144)
			(stroke
				(width 0.1)
				(type default)
			)
			(layer "B.Fab")
		)
		(pad "1" smd custom
			(at 0 0 90)
			(size 0.10414 0.10414)
			(layers "B.Cu" "B.Mask" "B.Paste")
			(net "PVNN_PCH_STBY")
			(options
				(clearance outline)
				(anchor circle)
			)
			(primitives
				(gr_poly
					(pts
						(xy -0.20828 -0.08636) (xy -0.20828 0.08636) (xy -0.08636 0.20828) (xy 0.086614 0.20828) (xy 0.20828 0.086614)
						(xy 0.20828 -0.08636) (xy 0.08636 -0.20828) (xy -0.08636 -0.20828)
					)
					(width 0)
					(fill yes)
				)
			)
		)
		(pad "2" smd custom
			(at 0 0.8001 90)
			(size 0.10414 0.10414)
			(layers "B.Cu" "B.Mask" "B.Paste")
			(net "GND")
			(options
				(clearance outline)
				(anchor circle)
			)
			(primitives
				(gr_poly
					(pts
						(xy -0.20828 -0.08636) (xy -0.20828 0.08636) (xy -0.08636 0.20828) (xy 0.086614 0.20828) (xy 0.20828 0.086614)
						(xy 0.20828 -0.08636) (xy 0.08636 -0.20828) (xy -0.08636 -0.20828)
					)
					(width 0)
					(fill yes)
				)
			)
		)
		(zone
			(layer "B.Cu")
			(hatch none 0.5)
			(connect_pads
				(clearance 0)
			)
			(min_thickness 0.25)
			(keepout
				(tracks allowed)
				(vias not_allowed)
				(pads allowed)
				(copperpour not_allowed)
				(footprints allowed)
			)
			(placement
				(enabled no)
				(sheetname "")
			)
			(fill
				(thermal_gap 0.5)
				(thermal_bridge_width 0.5)
				(island_removal_mode 0)
			)
			(polygon
				(pts
					(xy 383.64922 -112.0648) (xy 383.64922 -112.4458) (xy 383.82448 -112.4458) (xy 383.824734 -112.0648)
				)
			)
		)
		(zone
			(layer "B.Cu")
			(hatch none 0.5)
			(connect_pads
				(clearance 0)
			)
			(min_thickness 0.25)
			(keepout
				(tracks not_allowed)
				(vias allowed)
				(pads allowed)
				(copperpour not_allowed)
				(footprints allowed)
			)
			(placement
				(enabled no)
				(sheetname "")
			)
			(fill
				(thermal_gap 0.5)
				(thermal_bridge_width 0.5)
				(island_removal_mode 0)
			)
			(polygon
				(pts
					(xy 383.64922 -112.0648) (xy 383.64922 -112.4458) (xy 383.82448 -112.4458) (xy 383.824734 -112.0648)
				)
			)
		)
	)
	(footprint ""
		(layer "B.Cu")
		(at 413.0294 -94.0308 180)
		(property "Reference" "R7G7"
			(at 0 0 0)
			(layer "B.SilkS")
			(hide yes)
			(effects
				(font
					(size 1.27 1.27)
				)
				(justify mirror)
			)
		)
		(property "Value" ""
			(at 0 0 0)
			(layer "B.Fab")
			(effects
				(font
					(size 1.27 1.27)
				)
				(justify mirror)
			)
		)
		(duplicate_pad_numbers_are_jumpers no)
		(fp_poly
			(pts
				(xy 0.2794 -0.1016) (xy -0.2794 -0.1016) (xy -0.2794 0.9906) (xy 0.2794 0.9906)
			)
			(stroke
				(width 0)
				(type default)
			)
			(fill no)
			(layer "B.CrtYd")
		)
		(fp_line
			(start 0.2794 0.9906)
			(end -0.2794 0.9906)
			(stroke
				(width 0.1)
				(type default)
			)
			(layer "B.Fab")
		)
		(fp_line
			(start 0.2794 -0.1016)
			(end 0.2794 0.9906)
			(stroke
				(width 0.1)
				(type default)
			)
			(layer "B.Fab")
		)
		(fp_line
			(start -0.2794 0.9906)
			(end -0.2794 -0.1016)
			(stroke
				(width 0.1)
				(type default)
			)
			(layer "B.Fab")
		)
		(fp_line
			(start -0.2794 -0.1016)
			(end 0.2794 -0.1016)
			(stroke
				(width 0.1)
				(type default)
			)
			(layer "B.Fab")
		)
		(pad "1" smd rect
			(at 0 0)
			(size 0.508 0.508)
			(layers "B.Cu" "B.Mask" "B.Paste")
			(net "P3V3")
		)
		(pad "2" smd rect
			(at 0 0.889)
			(size 0.508 0.508)
			(layers "B.Cu" "B.Mask" "B.Paste")
			(net "H_CPU0_MEMABC_MEMHOT")
		)
		(zone
			(layer "B.Cu")
			(hatch none 0.5)
			(connect_pads
				(clearance 0)
			)
			(min_thickness 0.25)
			(keepout
				(tracks not_allowed)
				(vias allowed)
				(pads allowed)
				(copperpour not_allowed)
				(footprints allowed)
			)
			(placement
				(enabled no)
				(sheetname "")
			)
			(fill
				(thermal_gap 0.5)
				(thermal_bridge_width 0.5)
				(island_removal_mode 0)
			)
			(polygon
				(pts
					(xy 412.7754 -94.6658) (xy 413.2834 -94.6658) (xy 413.2834 -94.2848) (xy 412.7754 -94.2848)
				)
			)
		)
		(zone
			(layer "B.Cu")
			(hatch none 0.5)
			(connect_pads
				(clearance 0)
			)
			(min_thickness 0.25)
			(keepout
				(tracks allowed)
				(vias not_allowed)
				(pads allowed)
				(copperpour not_allowed)
				(footprints allowed)
			)
			(placement
				(enabled no)
				(sheetname "")
			)
			(fill
				(thermal_gap 0.5)
				(thermal_bridge_width 0.5)
				(island_removal_mode 0)
			)
			(polygon
				(pts
					(xy 412.7754 -94.2848) (xy 413.2834 -94.2848) (xy 413.2834 -94.6658) (xy 412.7754 -94.6658)
				)
			)
		)
	)
)
